# S9S_MB_2U (Grand Teton) — schematic netlist excerpt (pin names and nets, part order shuffled) for the footprints in the layout excerpt that follows; sources: Cadence DE-HDL packaged netlist, KiCad conversion of 03242023_DA0F0TMBIJ0_F0T_Motherboard_J_brd_V01_OCP.brd

DB14  TDR_3P  EMPTY  pkg TH2  page 309
  GND  = T1_GND
  IO1  = TDR_SE_40_OHM_IN6
  IO2  = TDR_SE_40_OHM_IN6

R3777  Q_RES  0 5% CHIP  pkg 0402LF  page 240 : A = FM_UARTSW_LSB_N ; B = FM_UARTSW_LSB_R
R738  Q_RES  0 5% CHIP  pkg 0402LF  page 133 : A = FM_CPU0_SKTOCC_LVT3_N ; B = FM_CPU0_SKTOCC_N

(kicad_pcb
	(version 20260206)
	(generator "pcbnew")
	(generator_version "10.0")
	(general
		(thickness 1.6)
		(legacy_teardrops no)
	)
	(paper "A4")
	(title_block
		(title "03242023_DA0F0TMBIJ0_F0T_Motherboard_J_brd_V01_OCP.brd")
		(comment 1 "Grand Teton / footprints 5869-5871 of 6105")
	)
	(layers
		(0 "F.Cu" signal "TOP")
		(4 "In1.Cu" signal "GND")
		(6 "In2.Cu" signal "IN1")
		(8 "In3.Cu" signal "GND1")
		(10 "In4.Cu" signal "IN2")
		(12 "In5.Cu" signal "GND2")
		(14 "In6.Cu" signal "IN3")
		(16 "In7.Cu" signal "GND3")
		(18 "In8.Cu" signal "VCC")
		(20 "In9.Cu" signal "VCC1")
		(22 "In10.Cu" signal "GND4")
		(24 "In11.Cu" signal "IN4")
		(26 "In12.Cu" signal "GND5")
		(28 "In13.Cu" signal "IN5")
		(30 "In14.Cu" signal "GND6")
		(32 "In15.Cu" signal "IN6")
		(34 "In16.Cu" signal "GND7")
		(2 "B.Cu" signal "BOTTOM")
		(9 "F.Adhes" user "F.Adhesive")
		(11 "B.Adhes" user "B.Adhesive")
		(13 "F.Paste" user "Package Geometry/Pastemask Top")
		(15 "B.Paste" user "Package Geometry/Pastemask Bottom")
		(5 "F.SilkS" user "Ref Des/Silkscreen Top")
		(7 "B.SilkS" user "Ref Des/Silkscreen Bottom")
		(1 "F.Mask" user "Board Geometry/Soldermask Top")
		(3 "B.Mask" user "Board Geometry/Soldermask Bottom")
		(17 "Dwgs.User" user "User.Drawings")
		(19 "Cmts.User" user "User.Comments")
		(21 "Eco1.User" user "User.Eco1")
		(23 "Eco2.User" user "User.Eco2")
		(25 "Edge.Cuts" user "Board Geometry/Outline")
		(27 "Margin" user)
		(31 "F.CrtYd" user "Package Geometry/Place Bound Top")
		(29 "B.CrtYd" user "Package Geometry/Place Bound Bottom")
		(35 "F.Fab" user "Ref Des/Assembly Top")
		(33 "B.Fab" user "Ref Des/Assembly Bottom")
	)
	(footprint ""
		(layer "B.Cu")
		(at 201.962258 -192.64757)
		(property "Reference" "R738"
			(at 0 0 0)
			(layer "B.SilkS")
			(hide yes)
			(effects
				(font
					(size 1.27 1.27)
				)
				(justify mirror)
			)
		)
		(property "Value" ""
			(at 0 0 0)
			(layer "B.Fab")
			(effects
				(font
					(size 1.27 1.27)
				)
				(justify mirror)
			)
		)
		(duplicate_pad_numbers_are_jumpers no)
		(fp_line
			(start -0.7874 -0.4064)
			(end -0.7874 0.4064)
			(stroke
				(width 0.1524)
				(type default)
			)
			(layer "B.SilkS")
		)
		(fp_line
			(start -0.7874 0.4064)
			(end 0.7874 0.4064)
			(stroke
				(width 0.1524)
				(type default)
			)
			(layer "B.SilkS")
		)
		(fp_line
			(start 0.7874 -0.4064)
			(end -0.7874 -0.4064)
			(stroke
				(width 0.1524)
				(type default)
			)
			(layer "B.SilkS")
		)
		(fp_line
			(start 0.7874 0.4064)
			(end 0.7874 -0.4064)
			(stroke
				(width 0.1524)
				(type default)
			)
			(layer "B.SilkS")
		)
		(fp_line
			(start -0.67945 -0.3048)
			(end -0.67945 0.3048)
			(stroke
				(width 0.1)
				(type default)
			)
			(layer "B.Fab")
		)
		(fp_line
			(start -0.67945 0.3048)
			(end -0.120396 0.3048)
			(stroke
				(width 0.1)
				(type default)
			)
			(layer "B.Fab")
		)
		(fp_line
			(start -0.12065 -0.3048)
			(end -0.67945 -0.3048)
			(stroke
				(width 0.1)
				(type default)
			)
			(layer "B.Fab")
		)
		(fp_line
			(start -0.12065 -0.2794)
			(end -0.12065 -0.3048)
			(stroke
				(width 0.1)
				(type default)
			)
			(layer "B.Fab")
		)
		(fp_line
			(start -0.120396 0.2794)
			(end 0.12065 0.2794)
			(stroke
				(width 0.1)
				(type default)
			)
			(layer "B.Fab")
		)
		(fp_line
			(start -0.120396 0.3048)
			(end -0.120396 0.2794)
			(stroke
				(width 0.1)
				(type default)
			)
			(layer "B.Fab")
		)
		(fp_line
			(start 0.12065 -0.305054)
			(end 0.12065 -0.2794)
			(stroke
				(width 0.1)
				(type default)
			)
			(layer "B.Fab")
		)
		(fp_line
			(start 0.12065 -0.2794)
			(end -0.12065 -0.2794)
			(stroke
				(width 0.1)
				(type default)
			)
			(layer "B.Fab")
		)
		(fp_line
			(start 0.12065 0.2794)
			(end 0.12065 0.3048)
			(stroke
				(width 0.1)
				(type default)
			)
			(layer "B.Fab")
		)
		(fp_line
			(start 0.12065 0.3048)
			(end 0.67945 0.3048)
			(stroke
				(width 0.1)
				(type default)
			)
			(layer "B.Fab")
		)
		(fp_line
			(start 0.67945 -0.305054)
			(end 0.12065 -0.305054)
			(stroke
				(width 0.1)
				(type default)
			)
			(layer "B.Fab")
		)
		(fp_line
			(start 0.67945 0.3048)
			(end 0.67945 -0.305054)
			(stroke
				(width 0.1)
				(type default)
			)
			(layer "B.Fab")
		)
		(pad "1" smd circle
			(at 0.40005 0 180)
			(size 0 0)
			(layers "B.Cu" "B.Mask" "B.Paste")
			(net "FM_CPU0_SKTOCC_LVT3_N")
		)
		(pad "2" smd circle
			(at -0.40005 0 180)
			(size 0 0)
			(layers "B.Cu" "B.Mask" "B.Paste")
			(net "FM_CPU0_SKTOCC_N")
		)
	)
	(footprint ""
		(layer "B.Cu")
		(at 490.2708 -342.785192)
		(property "Reference" "DB14"
			(at 2.639822 -5.63118 270)
			(unlocked yes)
			(layer "B.SilkS")
			(effects
				(font
					(size 0.7874 0.5842)
					(thickness 0.1524)
				)
				(justify left mirror)
			)
		)
		(property "Value" ""
			(at 0 0 0)
			(layer "B.Fab")
			(effects
				(font
					(size 1.27 1.27)
				)
				(justify mirror)
			)
		)
		(duplicate_pad_numbers_are_jumpers no)
		(fp_line
			(start -3.330702 -4.771136)
			(end 0 4.011168)
			(stroke
				(width 0.1524)
				(type default)
			)
			(layer "B.SilkS")
		)
		(fp_line
			(start 0 4.011168)
			(end 3.330702 -4.771136)
			(stroke
				(width 0.1524)
				(type default)
			)
			(layer "B.SilkS")
		)
		(fp_line
			(start 3.330702 -4.771136)
			(end -3.330702 -4.771136)
			(stroke
				(width 0.1524)
				(type default)
			)
			(layer "B.SilkS")
		)
		(fp_line
			(start -3.330702 -4.771136)
			(end 0 4.011168)
			(stroke
				(width 0.1)
				(type default)
			)
			(layer "B.Fab")
		)
		(fp_line
			(start 0 4.011168)
			(end 3.330702 -4.771136)
			(stroke
				(width 0.1)
				(type default)
			)
			(layer "B.Fab")
		)
		(fp_line
			(start 3.330702 -4.771136)
			(end -3.330702 -4.771136)
			(stroke
				(width 0.1)
				(type default)
			)
			(layer "B.Fab")
		)
		(pad "1" thru_hole circle
			(at 0 0 180)
			(size 2.159 2.159)
			(drill 1.7018)
			(layers "*.Cu" "*.Mask")
			(remove_unused_layers no)
			(net "T1_GND")
			(clearance 0.0254)
			(thermal_gap 0.0254)
		)
		(pad "2" thru_hole circle
			(at 1.27 -3.348736 180)
			(size 2.159 2.159)
			(drill 1.7018)
			(layers "*.Cu" "*.Mask")
			(remove_unused_layers no)
			(net "TDR_SE_40_OHM_IN6")
			(clearance 0.0254)
			(thermal_gap 0.0254)
		)
		(pad "3" thru_hole circle
			(at -1.27 -3.348736 180)
			(size 2.159 2.159)
			(drill 1.7018)
			(layers "*.Cu" "*.Mask")
			(remove_unused_layers no)
			(net "TDR_SE_40_OHM_IN6")
			(clearance 0.0254)
			(thermal_gap 0.0254)
		)
	)
	(footprint ""
		(layer "B.Cu")
		(at 134.54888 -9.362948 -90)
		(property "Reference" "R3777"
			(at 0 0 90)
			(layer "B.SilkS")
			(hide yes)
			(effects
				(font
					(size 1.27 1.27)
				)
				(justify mirror)
			)
		)
		(property "Value" ""
			(at 0 0 90)
			(layer "B.Fab")
			(effects
				(font
					(size 1.27 1.27)
				)
				(justify mirror)
			)
		)
		(duplicate_pad_numbers_are_jumpers no)
		(fp_line
			(start -0.7874 0.4064)
			(end 0.7874 0.4064)
			(stroke
				(width 0.1524)
				(type default)
			)
			(layer "B.SilkS")
		)
		(fp_line
			(start 0.7874 0.4064)
			(end 0.7874 -0.4064)
			(stroke
				(width 0.1524)
				(type default)
			)
			(layer "B.SilkS")
		)
		(fp_line
			(start -0.7874 -0.4064)
			(end -0.7874 0.4064)
			(stroke
				(width 0.1524)
				(type default)
			)
			(layer "B.SilkS")
		)
		(fp_line
			(start 0.7874 -0.4064)
			(end -0.7874 -0.4064)
			(stroke
				(width 0.1524)
				(type default)
			)
			(layer "B.SilkS")
		)
		(fp_line
			(start -0.67945 0.3048)
			(end -0.120396 0.3048)
			(stroke
				(width 0.1)
				(type default)
			)
			(layer "B.Fab")
		)
		(fp_line
			(start -0.120396 0.3048)
			(end -0.120396 0.2794)
			(stroke
				(width 0.1)
				(type default)
			)
			(layer "B.Fab")
		)
		(fp_line
			(start 0.12065 0.3048)
			(end 0.67945 0.3048)
			(stroke
				(width 0.1)
				(type default)
			)
			(layer "B.Fab")
		)
		(fp_line
			(start 0.67945 0.3048)
			(end 0.67945 -0.305054)
			(stroke
				(width 0.1)
				(type default)
			)
			(layer "B.Fab")
		)
		(fp_line
			(start -0.120396 0.2794)
			(end 0.12065 0.2794)
			(stroke
				(width 0.1)
				(type default)
			)
			(layer "B.Fab")
		)
		(fp_line
			(start 0.12065 0.2794)
			(end 0.12065 0.3048)
			(stroke
				(width 0.1)
				(type default)
			)
			(layer "B.Fab")
		)
		(fp_line
			(start -0.12065 -0.2794)
			(end -0.12065 -0.3048)
			(stroke
				(width 0.1)
				(type default)
			)
			(layer "B.Fab")
		)
		(fp_line
			(start 0.12065 -0.2794)
			(end -0.12065 -0.2794)
			(stroke
				(width 0.1)
				(type default)
			)
			(layer "B.Fab")
		)
		(fp_line
			(start -0.67945 -0.3048)
			(end -0.67945 0.3048)
			(stroke
				(width 0.1)
				(type default)
			)
			(layer "B.Fab")
		)
		(fp_line
			(start -0.12065 -0.3048)
			(end -0.67945 -0.3048)
			(stroke
				(width 0.1)
				(type default)
			)
			(layer "B.Fab")
		)
		(fp_line
			(start 0.12065 -0.305054)
			(end 0.12065 -0.2794)
			(stroke
				(width 0.1)
				(type default)
			)
			(layer "B.Fab")
		)
		(fp_line
			(start 0.67945 -0.305054)
			(end 0.12065 -0.305054)
			(stroke
				(width 0.1)
				(type default)
			)
			(layer "B.Fab")
		)
		(pad "1" smd circle
			(at 0.40005 0 90)
			(size 0 0)
			(layers "B.Cu" "B.Mask" "B.Paste")
			(net "FM_UARTSW_LSB_N")
		)
		(pad "2" smd circle
			(at -0.40005 0 90)
			(size 0 0)
			(layers "B.Cu" "B.Mask" "B.Paste")
			(net "FM_UARTSW_LSB_R")
		)
	)
)
